(kicad_pcb
	(version 20260206)
	(generator "pcbnew")
	(generator_version "10.0")
	(general
		(thickness 1.6)
		(legacy_teardrops no)
	)
	(paper "A4")
	(title_block
		(title "Wiwynn_Tioga_Pass_MB.brd")
		(comment 1 "Tioga Pass / footprint 830 of 4770 (J1A1), pads 1-123 of 291")
	)
	(layers
		(0 "F.Cu" signal "TOP")
		(4 "In1.Cu" signal "L2GND")
		(6 "In2.Cu" signal "L3")
		(8 "In3.Cu" signal "L4GND")
		(10 "In4.Cu" signal "L5")
		(12 "In5.Cu" signal "L6GND")
		(14 "In6.Cu" signal "L7VCC")
		(16 "In7.Cu" signal "L8VCC")
		(18 "In8.Cu" signal "L9GND")
		(20 "In9.Cu" signal "L10")
		(22 "In10.Cu" signal "L11GND")
		(24 "In11.Cu" signal "L12")
		(26 "In12.Cu" signal "L13GND")
		(2 "B.Cu" signal "BOTTOM")
		(9 "F.Adhes" user "F.Adhesive")
		(11 "B.Adhes" user "B.Adhesive")
		(13 "F.Paste" user "Package Geometry/Pastemask Top")
		(15 "B.Paste" user "Package Geometry/Pastemask Bottom")
		(5 "F.SilkS" user "Ref Des/Silkscreen Top")
		(7 "B.SilkS" user "Ref Des/Silkscreen Bottom")
		(1 "F.Mask" user "Board Geometry/Soldermask Top")
		(3 "B.Mask" user "Board Geometry/Soldermask Bottom")
		(17 "Dwgs.User" user "User.Drawings")
		(19 "Cmts.User" user "User.Comments")
		(21 "Eco1.User" user "User.Eco1")
		(23 "Eco2.User" user "User.Eco2")
		(25 "Edge.Cuts" user "Board Geometry/Outline")
		(27 "Margin" user)
		(31 "F.CrtYd" user "Package Geometry/Place Bound Top")
		(29 "B.CrtYd" user "Package Geometry/Place Bound Bottom")
		(35 "F.Fab" user "Ref Des/Assembly Top")
		(33 "B.Fab" user "Ref Des/Assembly Bottom")
	)
	(footprint ""
		(layer "F.Cu")
		(at 29.699458 -152.273 90)
		(property "Reference" "J1A1"
			(at -2.572512 42.563542 0)
			(unlocked yes)
			(layer "F.SilkS")
			(effects
				(font
					(size 0.7874 0.5842)
					(thickness 0.1524)
				)
				(justify left)
			)
		)
		(property "Value" ""
			(at 0 0 90)
			(layer "F.Fab")
			(effects
				(font
					(size 1.27 1.27)
				)
			)
		)
		(duplicate_pad_numbers_are_jumpers no)
		(pad "" thru_hole circle
			(at 2.29997 -5.649976 90)
			(size 2.8194 2.8194)
			(drill 2.4384)
			(layers "*.Cu" "*.Mask")
			(remove_unused_layers no)
			(clearance 0.127)
			(thermal_gap 0.127)
		)
		(pad "" thru_hole oval
			(at 2.29997 68.90004 90)
			(size 2.8194 1.5748)
			(drill oval 2.4384 1.1938)
			(layers "*.Cu" "*.Mask")
			(remove_unused_layers no)
			(clearance 0.127)
			(thermal_gap 0.127)
		)
		(pad "" thru_hole circle
			(at 2.29997 132.299964 90)
			(size 2.8194 2.8194)
			(drill 2.4384)
			(layers "*.Cu" "*.Mask")
			(remove_unused_layers no)
			(clearance 0.127)
			(thermal_gap 0.127)
		)
		(pad "1" smd rect
			(at 0 0 90)
			(size 1.8034 0.508)
			(layers "F.Cu" "F.Mask" "F.Paste")
			(net "P12V_NVDIMM_KLM")
		)
		(pad "2" smd rect
			(at 0 0.849884 90)
			(size 1.8034 0.508)
			(layers "F.Cu" "F.Mask" "F.Paste")
			(net "GND")
		)
		(pad "3" smd rect
			(at 0 1.700022 90)
			(size 1.8034 0.508)
			(layers "F.Cu" "F.Mask" "F.Paste")
			(net "M_M_DQ<5>")
		)
		(pad "4" smd rect
			(at 0 2.549906 90)
			(size 1.8034 0.508)
			(layers "F.Cu" "F.Mask" "F.Paste")
			(net "GND")
		)
		(pad "5" smd rect
			(at 0 3.400044 90)
			(size 1.8034 0.508)
			(layers "F.Cu" "F.Mask" "F.Paste")
			(net "M_M_DQ<1>")
		)
		(pad "6" smd rect
			(at 0 4.249928 90)
			(size 1.8034 0.508)
			(layers "F.Cu" "F.Mask" "F.Paste")
			(net "GND")
		)
		(pad "7" smd rect
			(at 0 5.100066 90)
			(size 1.8034 0.508)
			(layers "F.Cu" "F.Mask" "F.Paste")
			(net "M_M_DQS_DP<9>")
		)
		(pad "8" smd rect
			(at 0 5.94995 90)
			(size 1.8034 0.508)
			(layers "F.Cu" "F.Mask" "F.Paste")
			(net "M_M_DQS_DN<9>")
		)
		(pad "9" smd rect
			(at 0 6.800088 90)
			(size 1.8034 0.508)
			(layers "F.Cu" "F.Mask" "F.Paste")
			(net "GND")
		)
		(pad "10" smd rect
			(at 0 7.649972 90)
			(size 1.8034 0.508)
			(layers "F.Cu" "F.Mask" "F.Paste")
			(net "M_M_DQ<7>")
		)
		(pad "11" smd rect
			(at 0 8.50011 90)
			(size 1.8034 0.508)
			(layers "F.Cu" "F.Mask" "F.Paste")
			(net "GND")
		)
		(pad "12" smd rect
			(at 0 9.349994 90)
			(size 1.8034 0.508)
			(layers "F.Cu" "F.Mask" "F.Paste")
			(net "M_M_DQ<3>")
		)
		(pad "13" smd rect
			(at 0 10.199878 90)
			(size 1.8034 0.508)
			(layers "F.Cu" "F.Mask" "F.Paste")
			(net "GND")
		)
		(pad "14" smd rect
			(at 0 11.050016 90)
			(size 1.8034 0.508)
			(layers "F.Cu" "F.Mask" "F.Paste")
			(net "M_M_DQ<13>")
		)
		(pad "15" smd rect
			(at 0 11.8999 90)
			(size 1.8034 0.508)
			(layers "F.Cu" "F.Mask" "F.Paste")
			(net "GND")
		)
		(pad "16" smd rect
			(at 0 12.750038 90)
			(size 1.8034 0.508)
			(layers "F.Cu" "F.Mask" "F.Paste")
			(net "M_M_DQ<9>")
		)
		(pad "17" smd rect
			(at 0 13.599922 90)
			(size 1.8034 0.508)
			(layers "F.Cu" "F.Mask" "F.Paste")
			(net "GND")
		)
		(pad "18" smd rect
			(at 0 14.45006 90)
			(size 1.8034 0.508)
			(layers "F.Cu" "F.Mask" "F.Paste")
			(net "M_M_DQS_DP<10>")
		)
		(pad "19" smd rect
			(at 0 15.299944 90)
			(size 1.8034 0.508)
			(layers "F.Cu" "F.Mask" "F.Paste")
			(net "M_M_DQS_DN<10>")
		)
		(pad "20" smd rect
			(at 0 16.150082 90)
			(size 1.8034 0.508)
			(layers "F.Cu" "F.Mask" "F.Paste")
			(net "GND")
		)
		(pad "21" smd rect
			(at 0 16.999966 90)
			(size 1.8034 0.508)
			(layers "F.Cu" "F.Mask" "F.Paste")
			(net "M_M_DQ<15>")
		)
		(pad "22" smd rect
			(at 0 17.850104 90)
			(size 1.8034 0.508)
			(layers "F.Cu" "F.Mask" "F.Paste")
			(net "GND")
		)
		(pad "23" smd rect
			(at 0 18.699988 90)
			(size 1.8034 0.508)
			(layers "F.Cu" "F.Mask" "F.Paste")
			(net "M_M_DQ<11>")
		)
		(pad "24" smd rect
			(at 0 19.550126 90)
			(size 1.8034 0.508)
			(layers "F.Cu" "F.Mask" "F.Paste")
			(net "GND")
		)
		(pad "25" smd rect
			(at 0 20.40001 90)
			(size 1.8034 0.508)
			(layers "F.Cu" "F.Mask" "F.Paste")
			(net "M_M_DQ<21>")
		)
		(pad "26" smd rect
			(at 0 21.249894 90)
			(size 1.8034 0.508)
			(layers "F.Cu" "F.Mask" "F.Paste")
			(net "GND")
		)
		(pad "27" smd rect
			(at 0 22.100032 90)
			(size 1.8034 0.508)
			(layers "F.Cu" "F.Mask" "F.Paste")
			(net "M_M_DQ<17>")
		)
		(pad "28" smd rect
			(at 0 22.949916 90)
			(size 1.8034 0.508)
			(layers "F.Cu" "F.Mask" "F.Paste")
			(net "GND")
		)
		(pad "29" smd rect
			(at 0 23.800054 90)
			(size 1.8034 0.508)
			(layers "F.Cu" "F.Mask" "F.Paste")
			(net "M_M_DQS_DP<11>")
		)
		(pad "30" smd rect
			(at 0 24.649938 90)
			(size 1.8034 0.508)
			(layers "F.Cu" "F.Mask" "F.Paste")
			(net "M_M_DQS_DN<11>")
		)
		(pad "31" smd rect
			(at 0 25.500076 90)
			(size 1.8034 0.508)
			(layers "F.Cu" "F.Mask" "F.Paste")
			(net "GND")
		)
		(pad "32" smd rect
			(at 0 26.34996 90)
			(size 1.8034 0.508)
			(layers "F.Cu" "F.Mask" "F.Paste")
			(net "M_M_DQ<23>")
		)
		(pad "33" smd rect
			(at 0 27.200098 90)
			(size 1.8034 0.508)
			(layers "F.Cu" "F.Mask" "F.Paste")
			(net "GND")
		)
		(pad "34" smd rect
			(at 0 28.049982 90)
			(size 1.8034 0.508)
			(layers "F.Cu" "F.Mask" "F.Paste")
			(net "M_M_DQ<19>")
		)
		(pad "35" smd rect
			(at 0 28.90012 90)
			(size 1.8034 0.508)
			(layers "F.Cu" "F.Mask" "F.Paste")
			(net "GND")
		)
		(pad "36" smd rect
			(at 0 29.750004 90)
			(size 1.8034 0.508)
			(layers "F.Cu" "F.Mask" "F.Paste")
			(net "M_M_DQ<29>")
		)
		(pad "37" smd rect
			(at 0 30.599888 90)
			(size 1.8034 0.508)
			(layers "F.Cu" "F.Mask" "F.Paste")
			(net "GND")
		)
		(pad "38" smd rect
			(at 0 31.450026 90)
			(size 1.8034 0.508)
			(layers "F.Cu" "F.Mask" "F.Paste")
			(net "M_M_DQ<25>")
		)
		(pad "39" smd rect
			(at 0 32.29991 90)
			(size 1.8034 0.508)
			(layers "F.Cu" "F.Mask" "F.Paste")
			(net "GND")
		)
		(pad "40" smd rect
			(at 0 33.150048 90)
			(size 1.8034 0.508)
			(layers "F.Cu" "F.Mask" "F.Paste")
			(net "M_M_DQS_DP<12>")
		)
		(pad "41" smd rect
			(at 0 33.999932 90)
			(size 1.8034 0.508)
			(layers "F.Cu" "F.Mask" "F.Paste")
			(net "M_M_DQS_DN<12>")
		)
		(pad "42" smd rect
			(at 0 34.85007 90)
			(size 1.8034 0.508)
			(layers "F.Cu" "F.Mask" "F.Paste")
			(net "GND")
		)
		(pad "43" smd rect
			(at 0 35.699954 90)
			(size 1.8034 0.508)
			(layers "F.Cu" "F.Mask" "F.Paste")
			(net "M_M_DQ<31>")
		)
		(pad "44" smd rect
			(at 0 36.550092 90)
			(size 1.8034 0.508)
			(layers "F.Cu" "F.Mask" "F.Paste")
			(net "GND")
		)
		(pad "45" smd rect
			(at 0 37.399976 90)
			(size 1.8034 0.508)
			(layers "F.Cu" "F.Mask" "F.Paste")
			(net "M_M_DQ<27>")
		)
		(pad "46" smd rect
			(at 0 38.250114 90)
			(size 1.8034 0.508)
			(layers "F.Cu" "F.Mask" "F.Paste")
			(net "GND")
		)
		(pad "47" smd rect
			(at 0 39.099998 90)
			(size 1.8034 0.508)
			(layers "F.Cu" "F.Mask" "F.Paste")
			(net "M_M_ECC<5>")
		)
		(pad "48" smd rect
			(at 0 39.949882 90)
			(size 1.8034 0.508)
			(layers "F.Cu" "F.Mask" "F.Paste")
			(net "GND")
		)
		(pad "49" smd rect
			(at 0 40.80002 90)
			(size 1.8034 0.508)
			(layers "F.Cu" "F.Mask" "F.Paste")
			(net "M_M_ECC<1>")
		)
		(pad "50" smd rect
			(at 0 41.649904 90)
			(size 1.8034 0.508)
			(layers "F.Cu" "F.Mask" "F.Paste")
			(net "GND")
		)
		(pad "51" smd rect
			(at 0 42.500042 90)
			(size 1.8034 0.508)
			(layers "F.Cu" "F.Mask" "F.Paste")
			(net "M_M_DQS_DP<17>")
		)
		(pad "52" smd rect
			(at 0 43.349926 90)
			(size 1.8034 0.508)
			(layers "F.Cu" "F.Mask" "F.Paste")
			(net "M_M_DQS_DN<17>")
		)
		(pad "53" smd rect
			(at 0 44.200064 90)
			(size 1.8034 0.508)
			(layers "F.Cu" "F.Mask" "F.Paste")
			(net "GND")
		)
		(pad "54" smd rect
			(at 0 45.049948 90)
			(size 1.8034 0.508)
			(layers "F.Cu" "F.Mask" "F.Paste")
			(net "M_M_ECC<7>")
		)
		(pad "55" smd rect
			(at 0 45.900086 90)
			(size 1.8034 0.508)
			(layers "F.Cu" "F.Mask" "F.Paste")
			(net "GND")
		)
		(pad "56" smd rect
			(at 0 46.74997 90)
			(size 1.8034 0.508)
			(layers "F.Cu" "F.Mask" "F.Paste")
			(net "M_M_ECC<3>")
		)
		(pad "57" smd rect
			(at 0 47.600108 90)
			(size 1.8034 0.508)
			(layers "F.Cu" "F.Mask" "F.Paste")
			(net "GND")
		)
		(pad "58" smd rect
			(at 0 48.449992 90)
			(size 1.8034 0.508)
			(layers "F.Cu" "F.Mask" "F.Paste")
			(net "M_KLM_RST_N")
		)
		(pad "59" smd rect
			(at 0 49.299876 90)
			(size 1.8034 0.508)
			(layers "F.Cu" "F.Mask" "F.Paste")
			(net "PVDDQ_KLM")
		)
		(pad "60" smd rect
			(at 0 50.150014 90)
			(size 1.8034 0.508)
			(layers "F.Cu" "F.Mask" "F.Paste")
			(net "M_M_CKE<0>")
		)
		(pad "61" smd rect
			(at 0 50.999898 90)
			(size 1.8034 0.508)
			(layers "F.Cu" "F.Mask" "F.Paste")
			(net "PVDDQ_KLM")
		)
		(pad "62" smd rect
			(at 0 51.850036 90)
			(size 1.8034 0.508)
			(layers "F.Cu" "F.Mask" "F.Paste")
			(net "M_M_ACT_N")
		)
		(pad "63" smd rect
			(at 0 52.69992 90)
			(size 1.8034 0.508)
			(layers "F.Cu" "F.Mask" "F.Paste")
			(net "M_M_BG<0>")
		)
		(pad "64" smd rect
			(at 0 53.550058 90)
			(size 1.8034 0.508)
			(layers "F.Cu" "F.Mask" "F.Paste")
			(net "PVDDQ_KLM")
		)
		(pad "65" smd rect
			(at 0 54.399942 90)
			(size 1.8034 0.508)
			(layers "F.Cu" "F.Mask" "F.Paste")
			(net "M_M_MA<12>")
		)
		(pad "66" smd rect
			(at 0 55.25008 90)
			(size 1.8034 0.508)
			(layers "F.Cu" "F.Mask" "F.Paste")
			(net "M_M_MA<9>")
		)
		(pad "67" smd rect
			(at 0 56.099964 90)
			(size 1.8034 0.508)
			(layers "F.Cu" "F.Mask" "F.Paste")
			(net "PVDDQ_KLM")
		)
		(pad "68" smd rect
			(at 0 56.950102 90)
			(size 1.8034 0.508)
			(layers "F.Cu" "F.Mask" "F.Paste")
			(net "M_M_MA<8>")
		)
		(pad "69" smd rect
			(at 0 57.799986 90)
			(size 1.8034 0.508)
			(layers "F.Cu" "F.Mask" "F.Paste")
			(net "M_M_MA<6>")
		)
		(pad "70" smd rect
			(at 0 58.650124 90)
			(size 1.8034 0.508)
			(layers "F.Cu" "F.Mask" "F.Paste")
			(net "PVDDQ_KLM")
		)
		(pad "71" smd rect
			(at 0 59.500008 90)
			(size 1.8034 0.508)
			(layers "F.Cu" "F.Mask" "F.Paste")
			(net "M_M_MA<3>")
		)
		(pad "72" smd rect
			(at 0 60.349892 90)
			(size 1.8034 0.508)
			(layers "F.Cu" "F.Mask" "F.Paste")
			(net "M_M_MA<1>")
		)
		(pad "73" smd rect
			(at 0 61.20003 90)
			(size 1.8034 0.508)
			(layers "F.Cu" "F.Mask" "F.Paste")
			(net "PVDDQ_KLM")
		)
		(pad "74" smd rect
			(at 0 62.049914 90)
			(size 1.8034 0.508)
			(layers "F.Cu" "F.Mask" "F.Paste")
			(net "M_M_CLK_DP<0>")
		)
		(pad "75" smd rect
			(at 0 62.900052 90)
			(size 1.8034 0.508)
			(layers "F.Cu" "F.Mask" "F.Paste")
			(net "M_M_CLK_DN<0>")
		)
		(pad "76" smd rect
			(at 0 63.749936 90)
			(size 1.8034 0.508)
			(layers "F.Cu" "F.Mask" "F.Paste")
			(net "PVDDQ_KLM")
		)
		(pad "77" smd rect
			(at 0 64.600074 90)
			(size 1.8034 0.508)
			(layers "F.Cu" "F.Mask" "F.Paste")
			(net "PVTT_KLM")
		)
		(pad "78" smd rect
			(at 0 70.550024 90)
			(size 1.8034 0.508)
			(layers "F.Cu" "F.Mask" "F.Paste")
			(net "FM_DIMM_EVENT_COD_N")
		)
		(pad "79" smd rect
			(at 0 71.399908 90)
			(size 1.8034 0.508)
			(layers "F.Cu" "F.Mask" "F.Paste")
			(net "M_M_MA<0>")
		)
		(pad "80" smd rect
			(at 0 72.250046 90)
			(size 1.8034 0.508)
			(layers "F.Cu" "F.Mask" "F.Paste")
			(net "PVDDQ_KLM")
		)
		(pad "81" smd rect
			(at 0 73.09993 90)
			(size 1.8034 0.508)
			(layers "F.Cu" "F.Mask" "F.Paste")
			(net "M_M_BA<0>")
		)
		(pad "82" smd rect
			(at 0 73.950068 90)
			(size 1.8034 0.508)
			(layers "F.Cu" "F.Mask" "F.Paste")
			(net "M_M_MA<16>")
		)
		(pad "83" smd rect
			(at 0 74.799952 90)
			(size 1.8034 0.508)
			(layers "F.Cu" "F.Mask" "F.Paste")
			(net "PVDDQ_KLM")
		)
		(pad "84" smd rect
			(at 0 75.65009 90)
			(size 1.8034 0.508)
			(layers "F.Cu" "F.Mask" "F.Paste")
			(net "M_M_CS_N<0>")
		)
		(pad "85" smd rect
			(at 0 76.499974 90)
			(size 1.8034 0.508)
			(layers "F.Cu" "F.Mask" "F.Paste")
			(net "PVDDQ_KLM")
		)
		(pad "86" smd rect
			(at 0 77.350112 90)
			(size 1.8034 0.508)
			(layers "F.Cu" "F.Mask" "F.Paste")
			(net "M_M_MA<15>")
		)
		(pad "87" smd rect
			(at 0 78.199996 90)
			(size 1.8034 0.508)
			(layers "F.Cu" "F.Mask" "F.Paste")
			(net "M_M_ODT<0>")
		)
		(pad "88" smd rect
			(at 0 79.04988 90)
			(size 1.8034 0.508)
			(layers "F.Cu" "F.Mask" "F.Paste")
			(net "PVDDQ_KLM")
		)
		(pad "89" smd rect
			(at 0 79.900018 90)
			(size 1.8034 0.508)
			(layers "F.Cu" "F.Mask" "F.Paste")
			(net "M_M_CS_N<1>")
		)
		(pad "90" smd rect
			(at 0 80.749902 90)
			(size 1.8034 0.508)
			(layers "F.Cu" "F.Mask" "F.Paste")
			(net "PVDDQ_KLM")
		)
		(pad "91" smd rect
			(at 0 81.60004 90)
			(size 1.8034 0.508)
			(layers "F.Cu" "F.Mask" "F.Paste")
			(net "M_M_ODT<1>")
		)
		(pad "92" smd rect
			(at 0 82.449924 90)
			(size 1.8034 0.508)
			(layers "F.Cu" "F.Mask" "F.Paste")
			(net "PVDDQ_KLM")
		)
		(pad "93" smd rect
			(at 0 83.300062 90)
			(size 1.8034 0.508)
			(layers "F.Cu" "F.Mask" "F.Paste")
			(net "M_M_CS_N<2>")
		)
		(pad "94" smd rect
			(at 0 84.149946 90)
			(size 1.8034 0.508)
			(layers "F.Cu" "F.Mask" "F.Paste")
			(net "GND")
		)
		(pad "95" smd rect
			(at 0 85.000084 90)
			(size 1.8034 0.508)
			(layers "F.Cu" "F.Mask" "F.Paste")
			(net "M_M_DQ<37>")
		)
		(pad "96" smd rect
			(at 0 85.849968 90)
			(size 1.8034 0.508)
			(layers "F.Cu" "F.Mask" "F.Paste")
			(net "GND")
		)
		(pad "97" smd rect
			(at 0 86.700106 90)
			(size 1.8034 0.508)
			(layers "F.Cu" "F.Mask" "F.Paste")
			(net "M_M_DQ<33>")
		)
		(pad "98" smd rect
			(at 0 87.54999 90)
			(size 1.8034 0.508)
			(layers "F.Cu" "F.Mask" "F.Paste")
			(net "GND")
		)
		(pad "99" smd rect
			(at 0 88.399874 90)
			(size 1.8034 0.508)
			(layers "F.Cu" "F.Mask" "F.Paste")
			(net "M_M_DQS_DP<13>")
		)
		(pad "100" smd rect
			(at 0 89.250012 90)
			(size 1.8034 0.508)
			(layers "F.Cu" "F.Mask" "F.Paste")
			(net "M_M_DQS_DN<13>")
		)
		(pad "101" smd rect
			(at 0 90.099896 90)
			(size 1.8034 0.508)
			(layers "F.Cu" "F.Mask" "F.Paste")
			(net "GND")
		)
		(pad "102" smd rect
			(at 0 90.950034 90)
			(size 1.8034 0.508)
			(layers "F.Cu" "F.Mask" "F.Paste")
			(net "M_M_DQ<39>")
		)
		(pad "103" smd rect
			(at 0 91.799918 90)
			(size 1.8034 0.508)
			(layers "F.Cu" "F.Mask" "F.Paste")
			(net "GND")
		)
		(pad "104" smd rect
			(at 0 92.650056 90)
			(size 1.8034 0.508)
			(layers "F.Cu" "F.Mask" "F.Paste")
			(net "M_M_DQ<35>")
		)
		(pad "105" smd rect
			(at 0 93.49994 90)
			(size 1.8034 0.508)
			(layers "F.Cu" "F.Mask" "F.Paste")
			(net "GND")
		)
		(pad "106" smd rect
			(at 0 94.350078 90)
			(size 1.8034 0.508)
			(layers "F.Cu" "F.Mask" "F.Paste")
			(net "M_M_DQ<45>")
		)
		(pad "107" smd rect
			(at 0 95.199962 90)
			(size 1.8034 0.508)
			(layers "F.Cu" "F.Mask" "F.Paste")
			(net "GND")
		)
		(pad "108" smd rect
			(at 0 96.0501 90)
			(size 1.8034 0.508)
			(layers "F.Cu" "F.Mask" "F.Paste")
			(net "M_M_DQ<41>")
		)
		(pad "109" smd rect
			(at 0 96.899984 90)
			(size 1.8034 0.508)
			(layers "F.Cu" "F.Mask" "F.Paste")
			(net "GND")
		)
		(pad "110" smd rect
			(at 0 97.750122 90)
			(size 1.8034 0.508)
			(layers "F.Cu" "F.Mask" "F.Paste")
			(net "M_M_DQS_DP<14>")
		)
		(pad "111" smd rect
			(at 0 98.600006 90)
			(size 1.8034 0.508)
			(layers "F.Cu" "F.Mask" "F.Paste")
			(net "M_M_DQS_DN<14>")
		)
		(pad "112" smd rect
			(at 0 99.44989 90)
			(size 1.8034 0.508)
			(layers "F.Cu" "F.Mask" "F.Paste")
			(net "GND")
		)
		(pad "113" smd rect
			(at 0 100.300028 90)
			(size 1.8034 0.508)
			(layers "F.Cu" "F.Mask" "F.Paste")
			(net "M_M_DQ<47>")
		)
		(pad "114" smd rect
			(at 0 101.149912 90)
			(size 1.8034 0.508)
			(layers "F.Cu" "F.Mask" "F.Paste")
			(net "GND")
		)
		(pad "115" smd rect
			(at 0 102.00005 90)
			(size 1.8034 0.508)
			(layers "F.Cu" "F.Mask" "F.Paste")
			(net "M_M_DQ<43>")
		)
		(pad "116" smd rect
			(at 0 102.849934 90)
			(size 1.8034 0.508)
			(layers "F.Cu" "F.Mask" "F.Paste")
			(net "GND")
		)
		(pad "117" smd rect
			(at 0 103.700072 90)
			(size 1.8034 0.508)
			(layers "F.Cu" "F.Mask" "F.Paste")
			(net "M_M_DQ<53>")
		)
		(pad "118" smd rect
			(at 0 104.549956 90)
			(size 1.8034 0.508)
			(layers "F.Cu" "F.Mask" "F.Paste")
			(net "GND")
		)
		(pad "119" smd rect
			(at 0 105.400094 90)
			(size 1.8034 0.508)
			(layers "F.Cu" "F.Mask" "F.Paste")
			(net "M_M_DQ<49>")
		)
		(pad "120" smd rect
			(at 0 106.249978 90)
			(size 1.8034 0.508)
			(layers "F.Cu" "F.Mask" "F.Paste")
			(net "GND")
		)
	)
)
